(kicad_pcb
	(version 20241229)
	(generator "pcbnew")
	(generator_version "9.0")
	(general
		(thickness 1.61)
		(legacy_teardrops no)
	)
	(paper "A3")
	(title_block
		(title "SO-DIMM DDR5 Tester")
		(date "2025-11-26")
		(rev "1.3.0")
		(comment 9 "footprints 262-266 of 627")
	)
	(layers
		(0 "F.Cu" signal)
		(4 "In1.Cu" power)
		(6 "In2.Cu" mixed)
		(8 "In3.Cu" power)
		(10 "In4.Cu" mixed)
		(12 "In5.Cu" power)
		(14 "In6.Cu" mixed)
		(16 "In7.Cu" power)
		(18 "In8.Cu" power)
		(20 "In9.Cu" mixed)
		(22 "In10.Cu" power)
		(2 "B.Cu" signal)
		(9 "F.Adhes" user "F.Adhesive")
		(11 "B.Adhes" user "B.Adhesive")
		(13 "F.Paste" user)
		(15 "B.Paste" user)
		(5 "F.SilkS" user "F.Silkscreen")
		(7 "B.SilkS" user "B.Silkscreen")
		(1 "F.Mask" user)
		(3 "B.Mask" user)
		(17 "Dwgs.User" user "User.Drawings")
		(19 "Cmts.User" user "User.Comments")
		(21 "Eco1.User" user "User.Eco1")
		(23 "Eco2.User" user "User.Eco2")
		(25 "Edge.Cuts" user)
		(27 "Margin" user)
		(31 "F.CrtYd" user "F.Courtyard")
		(29 "B.CrtYd" user "B.Courtyard")
		(35 "F.Fab" user)
		(33 "B.Fab" user)
	)
	(footprint "antmicro-footprints:C_0603_1608Metric"
		(layer "F.Cu")
		(at 118.1 205.3 180)
		(descr "Capacitor SMD 0603")
		(tags "capacitor 0603")
		(property "Reference" "C225"
			(at -1.42757 -1.000252 180)
			(layer "F.SilkS")
			(hide yes)
			(effects
				(font
					(size 0.7 0.7)
					(thickness 0.15)
				)
				(justify left bottom)
			)
		)
		(property "Value" "C_10u_25V_0603"
			(at -1.42757 1.770288 180)
			(layer "F.Fab")
			(effects
				(font
					(size 0.7 0.7)
					(thickness 0.15)
				)
				(justify left bottom)
			)
		)
		(property "Datasheet" "https://product.tdk.com/en/search/capacitor/ceramic/mlcc/info?part_no=C1608X5R1E106M080AC"
			(at 0 0 180)
			(layer "F.Fab")
			(hide yes)
			(effects
				(font
					(size 1.27 1.27)
					(thickness 0.15)
				)
			)
		)
		(property "Author" "Antmicro"
			(at 236.2 410.6 0)
			(layer "F.Fab")
			(hide yes)
			(effects
				(font
					(size 1 1)
					(thickness 0.15)
				)
			)
		)
		(property "Dielectric" ""
			(at 236.2 410.6 0)
			(layer "F.Fab")
			(hide yes)
			(effects
				(font
					(size 1 1)
					(thickness 0.15)
				)
			)
		)
		(property "License" "Apache-2.0"
			(at 236.2 410.6 0)
			(layer "F.Fab")
			(hide yes)
			(effects
				(font
					(size 1 1)
					(thickness 0.15)
				)
			)
		)
		(property "MPN" "C1608X5R1E106M080AC"
			(at 236.2 410.6 0)
			(layer "F.Fab")
			(hide yes)
			(effects
				(font
					(size 1 1)
					(thickness 0.15)
				)
			)
		)
		(property "Manufacturer" "TDK"
			(at 236.2 410.6 0)
			(layer "F.Fab")
			(hide yes)
			(effects
				(font
					(size 1 1)
					(thickness 0.15)
				)
			)
		)
		(property "Val" "10u/25V"
			(at 236.2 410.6 0)
			(layer "F.Fab")
			(hide yes)
			(effects
				(font
					(size 1 1)
					(thickness 0.15)
				)
			)
		)
		(property "Voltage" ""
			(at 236.2 410.6 0)
			(layer "F.Fab")
			(hide yes)
			(effects
				(font
					(size 1 1)
					(thickness 0.15)
				)
			)
		)
		(sheetname "/PCIe connector/")
		(sheetfile "pcie-connector.kicad_sch")
		(attr smd)
		(fp_line
			(start -0.3 0.3)
			(end 0.3 0.3)
			(stroke
				(width 0.15)
				(type solid)
			)
			(layer "F.SilkS")
		)
		(fp_line
			(start -0.3 -0.3)
			(end 0.3 -0.3)
			(stroke
				(width 0.15)
				(type solid)
			)
			(layer "F.SilkS")
		)
		(fp_rect
			(start -1.24 -0.7)
			(end 1.24 0.7)
			(stroke
				(width 0.05)
				(type solid)
			)
			(fill no)
			(layer "F.CrtYd")
		)
		(fp_rect
			(start -0.8 -0.4)
			(end 0.8 0.4)
			(stroke
				(width 0.15)
				(type solid)
			)
			(fill no)
			(layer "F.Fab")
		)
		(pad "1" smd roundrect
			(at -0.7 0 180)
			(size 0.6 0.8)
			(layers "F.Cu" "F.Mask" "F.Paste")
			(roundrect_rratio 0.2)
			(net 1 "GND")
			(pintype "passive")
		)
		(pad "2" smd roundrect
			(at 0.7 0 180)
			(size 0.6 0.8)
			(layers "F.Cu" "F.Mask" "F.Paste")
			(roundrect_rratio 0.2)
			(net 11 "+12V")
			(pintype "passive")
		)
	)
	(footprint "antmicro-footprints:NetTie-2_SMD_Pad0.127mm"
		(layer "F.Cu")
		(at 189.525 189.101)
		(descr "Net tie, 2 pin, 0.127mm  SMD pads")
		(tags "net tie")
		(property "Reference" "NT1"
			(at -0.128 -1.345 0)
			(layer "F.SilkS")
			(hide yes)
			(effects
				(font
					(size 0.7 0.7)
					(thickness 0.15)
				)
				(justify left bottom)
			)
		)
		(property "Value" "Net-Tie_P0.127mm"
			(at 0 1.199 0)
			(layer "F.Fab")
			(effects
				(font
					(size 0.7 0.7)
					(thickness 0.15)
				)
				(justify left bottom)
			)
		)
		(property "Author" "Antmicro"
			(at 0 0 0)
			(layer "F.Fab")
			(hide yes)
			(effects
				(font
					(size 1 1)
					(thickness 0.15)
				)
			)
		)
		(property "License" "Apache-2.0"
			(at 0 0 0)
			(layer "F.Fab")
			(hide yes)
			(effects
				(font
					(size 1 1)
					(thickness 0.15)
				)
			)
		)
		(property "MPN" ""
			(at 0 0 0)
			(layer "F.Fab")
			(hide yes)
			(effects
				(font
					(size 1 1)
					(thickness 0.15)
				)
			)
		)
		(property "Manufacturer" ""
			(at 0 0 0)
			(layer "F.Fab")
			(hide yes)
			(effects
				(font
					(size 1 1)
					(thickness 0.15)
				)
			)
		)
		(property ki_fp_filters "Net*Tie*")
		(sheetname "/Supply/")
		(sheetfile "supply.kicad_sch")
		(attr smd exclude_from_pos_files exclude_from_bom)
		(net_tie_pad_groups "1, 2")
		(fp_poly
			(pts
				(xy -0.0635 -0.0635) (xy 0.0625 -0.0635) (xy 0.0625 0.0635) (xy -0.0635 0.0635)
			)
			(stroke
				(width 0)
				(type solid)
			)
			(fill yes)
			(layer "F.Cu")
		)
		(pad "1" smd roundrect
			(at -0.127 0 180)
			(size 0.127 0.127)
			(layers "F.Cu")
			(roundrect_rratio 0.5)
			(chamfer_ratio 0)
			(chamfer top_left bottom_left)
			(net 86 "/Supply/MGTAVCC_SEN_+")
			(pinfunction "1")
			(pintype "passive")
		)
		(pad "2" smd roundrect
			(at 0.126 0)
			(size 0.127 0.127)
			(layers "F.Cu")
			(roundrect_rratio 0.5)
			(chamfer_ratio 0)
			(chamfer top_left bottom_left)
			(net 42 "/Supply/MGTAVCC_local")
			(pinfunction "2")
			(pintype "passive")
		)
	)
	(footprint "antmicro-footprints:LED_0603_1608Metric_G"
		(layer "F.Cu")
		(at 76.060501 126.276)
		(descr "LED SMD 0603 Green")
		(tags "LED SMD 0603 Green")
		(property "Reference" "D2"
			(at -0.001 -0.901 0)
			(layer "F.SilkS")
			(hide yes)
			(effects
				(font
					(size 0.7 0.7)
					(thickness 0.15)
				)
				(justify left bottom)
			)
		)
		(property "Value" "LED_G_0603_KP-1608CGCK"
			(at -0.001 1.599 0)
			(layer "F.Fab")
			(effects
				(font
					(size 0.7 0.7)
					(thickness 0.15)
				)
				(justify left bottom)
			)
		)
		(property "Datasheet" "http://www.farnell.com/datasheets/2045956.pdf"
			(at 0 0 0)
			(layer "F.Fab")
			(hide yes)
			(effects
				(font
					(size 1.27 1.27)
					(thickness 0.15)
				)
			)
		)
		(property "Author" "Antmicro"
			(at 0 0 0)
			(layer "F.Fab")
			(hide yes)
			(effects
				(font
					(size 1 1)
					(thickness 0.15)
				)
			)
		)
		(property "License" "Apache-2.0"
			(at 0 0 0)
			(layer "F.Fab")
			(hide yes)
			(effects
				(font
					(size 1 1)
					(thickness 0.15)
				)
			)
		)
		(property "MPN" "KP-1608CGCK"
			(at 0 0 0)
			(layer "F.Fab")
			(hide yes)
			(effects
				(font
					(size 1 1)
					(thickness 0.15)
				)
			)
		)
		(property "Manufacturer" "Kingbright"
			(at 0 0 0)
			(layer "F.Fab")
			(hide yes)
			(effects
				(font
					(size 1 1)
					(thickness 0.15)
				)
			)
		)
		(sheetname "/FPGA Config/")
		(sheetfile "fpga-config.kicad_sch")
		(attr smd)
		(fp_line
			(start -0.271 -0.349)
			(end 0.269 -0.349)
			(stroke
				(width 0.15)
				(type solid)
			)
			(layer "F.SilkS")
		)
		(fp_line
			(start -0.271 0.348)
			(end 0.269 0.348)
			(stroke
				(width 0.15)
				(type solid)
			)
			(layer "F.SilkS")
		)
		(fp_line
			(start -0.107 -0.201)
			(end -0.107 0.198)
			(stroke
				(width 0.1)
				(type solid)
			)
			(layer "F.SilkS")
		)
		(fp_line
			(start -0.107 -0.201)
			(end 0.092 -0.001)
			(stroke
				(width 0.1)
				(type solid)
			)
			(layer "F.SilkS")
		)
		(fp_line
			(start -0.107 -0.001)
			(end -0.291 -0.001)
			(stroke
				(width 0.1)
				(type solid)
			)
			(layer "F.SilkS")
		)
		(fp_line
			(start 0.092 -0.201)
			(end 0.092 0.198)
			(stroke
				(width 0.1)
				(type solid)
			)
			(layer "F.SilkS")
		)
		(fp_line
			(start 0.092 -0.001)
			(end -0.107 0.198)
			(stroke
				(width 0.1)
				(type solid)
			)
			(layer "F.SilkS")
		)
		(fp_line
			(start 0.092 -0.001)
			(end 0.292 -0.001)
			(stroke
				(width 0.1)
				(type solid)
			)
			(layer "F.SilkS")
		)
		(fp_line
			(start 1.249 0.319)
			(end 1.249 -0.321)
			(stroke
				(width 0.15)
				(type solid)
			)
			(layer "F.SilkS")
		)
		(fp_rect
			(start -1.2192 -0.6096)
			(end 1.27 0.6016)
			(stroke
				(width 0.05)
				(type solid)
			)
			(fill no)
			(layer "F.CrtYd")
		)
		(fp_line
			(start -0.849 0.025)
			(end -0.442 0.381)
			(stroke
				(width 0.15)
				(type solid)
			)
			(layer "F.Fab")
		)
		(fp_line
			(start -0.6 -0.001)
			(end -0.202 -0.001)
			(stroke
				(width 0.15)
				(type solid)
			)
			(layer "F.Fab")
		)
		(fp_line
			(start -0.202 -0.201)
			(end -0.202 -0.001)
			(stroke
				(width 0.15)
				(type solid)
			)
			(layer "F.Fab")
		)
		(fp_line
			(start -0.202 -0.001)
			(end -0.202 0.201)
			(stroke
				(width 0.15)
				(type solid)
			)
			(layer "F.Fab")
		)
		(fp_line
			(start -0.202 0.201)
			(end 0.1 -0.001)
			(stroke
				(width 0.15)
				(type solid)
			)
			(layer "F.Fab")
		)
		(fp_line
			(start 0.1 -0.001)
			(end -0.202 -0.201)
			(stroke
				(width 0.15)
				(type solid)
			)
			(layer "F.Fab")
		)
		(fp_line
			(start 0.198 -0.201)
			(end 0.198 -0.101)
			(stroke
				(width 0.15)
				(type solid)
			)
			(layer "F.Fab")
		)
		(fp_line
			(start 0.198 -0.001)
			(end 0.596 -0.001)
			(stroke
				(width 0.15)
				(type solid)
			)
			(layer "F.Fab")
		)
		(fp_line
			(start 0.198 0.201)
			(end 0.198 -0.101)
			(stroke
				(width 0.15)
				(type solid)
			)
			(layer "F.Fab")
		)
		(fp_rect
			(start -0.849 -0.401)
			(end 0.849 0.401)
			(stroke
				(width 0.15)
				(type solid)
			)
			(fill no)
			(layer "F.Fab")
		)
		(pad "1" smd rect
			(at -0.751 -0.001 180)
			(size 0.8 0.8)
			(layers "F.Cu" "F.Mask" "F.Paste")
			(net 200 "+3V3")
			(pinfunction "1")
			(pintype "passive")
		)
		(pad "2" smd rect
			(at 0.749 -0.001 180)
			(size 0.8 0.8)
			(layers "F.Cu" "F.Mask" "F.Paste")
			(net 305 "Net-(D2-Pad2)")
			(pinfunction "2")
			(pintype "passive")
		)
	)
	(footprint "antmicro-footprints:L_Bourns-SRP6050CA"
		(layer "F.Cu")
		(at 170.825501 188.176 180)
		(property "Reference" "L1"
			(at 0 -3.89 180)
			(layer "F.SilkS")
			(hide yes)
			(effects
				(font
					(size 0.7 0.7)
					(thickness 0.15)
				)
				(justify left bottom)
			)
		)
		(property "Value" "L_1u5_17A_Bourns-SRP6050CA"
			(at -0.025 4.85 180)
			(layer "F.Fab")
			(effects
				(font
					(size 0.7 0.7)
					(thickness 0.15)
				)
				(justify left bottom)
			)
		)
		(property "Datasheet" "https://www.bourns.com/docs/Product-Datasheets/SRP6050CA.pdf"
			(at 0 0 180)
			(layer "F.Fab")
			(hide yes)
			(effects
				(font
					(size 1.27 1.27)
					(thickness 0.15)
				)
			)
		)
		(property "Author" "Antmicro"
			(at 341.651002 376.352 0)
			(layer "F.Fab")
			(hide yes)
			(effects
				(font
					(size 1 1)
					(thickness 0.15)
				)
			)
		)
		(property "IMax" "17 A"
			(at 341.651002 376.352 0)
			(layer "F.Fab")
			(hide yes)
			(effects
				(font
					(size 1 1)
					(thickness 0.15)
				)
			)
		)
		(property "ISat" "19.5 A"
			(at 341.651002 376.352 0)
			(layer "F.Fab")
			(hide yes)
			(effects
				(font
					(size 1 1)
					(thickness 0.15)
				)
			)
		)
		(property "License" "Apache-2.0"
			(at 341.651002 376.352 0)
			(layer "F.Fab")
			(hide yes)
			(effects
				(font
					(size 1 1)
					(thickness 0.15)
				)
			)
		)
		(property "MPN" "SRP6050CA-1R5M"
			(at 341.651002 376.352 0)
			(layer "F.Fab")
			(hide yes)
			(effects
				(font
					(size 1 1)
					(thickness 0.15)
				)
			)
		)
		(property "Manufacturer" "Bourns"
			(at 341.651002 376.352 0)
			(layer "F.Fab")
			(hide yes)
			(effects
				(font
					(size 1 1)
					(thickness 0.15)
				)
			)
		)
		(property "Size" "6.6x6.6"
			(at 341.651002 376.352 0)
			(layer "F.Fab")
			(hide yes)
			(effects
				(font
					(size 1 1)
					(thickness 0.15)
				)
			)
		)
		(property "Val" "1u5/17A"
			(at 341.651002 376.352 0)
			(layer "F.Fab")
			(hide yes)
			(effects
				(font
					(size 1 1)
					(thickness 0.15)
				)
			)
		)
		(sheetname "/Supply/")
		(sheetfile "supply.kicad_sch")
		(attr smd)
		(fp_line
			(start 3.2 3.298)
			(end -3.2 3.298)
			(stroke
				(width 0.15)
				(type solid)
			)
			(layer "F.SilkS")
		)
		(fp_line
			(start 3.2 -3.301)
			(end 3.2 3.298)
			(stroke
				(width 0.15)
				(type solid)
			)
			(layer "F.SilkS")
		)
		(fp_line
			(start -3.2 -3.301)
			(end 3.2 -3.301)
			(stroke
				(width 0.15)
				(type solid)
			)
			(layer "F.SilkS")
		)
		(fp_line
			(start -3.2 -3.301)
			(end -3.2 3.298)
			(stroke
				(width 0.15)
				(type solid)
			)
			(layer "F.SilkS")
		)
		(fp_rect
			(start -3.45 -3.55)
			(end 3.45 3.55)
			(stroke
				(width 0.05)
				(type solid)
			)
			(fill no)
			(layer "F.CrtYd")
		)
		(fp_rect
			(start -3.202 -3.301)
			(end 3.2 3.298)
			(stroke
				(width 0.15)
				(type solid)
			)
			(fill no)
			(layer "F.Fab")
		)
		(pad "1" smd roundrect
			(at -2.025 0 180)
			(size 1.55 5.6)
			(layers "F.Cu" "F.Mask" "F.Paste")
			(roundrect_rratio 0.1)
			(net 66 "/Supply/1V0_SW")
			(pintype "passive")
		)
		(pad "2" smd roundrect
			(at 2.025 0 180)
			(size 1.55 5.6)
			(layers "F.Cu" "F.Mask" "F.Paste")
			(roundrect_rratio 0.1)
			(net 78 "/Supply/1V0_REG")
			(pintype "passive")
		)
	)
	(footprint "antmicro-footprints:TP_SMD_1mm"
		(layer "F.Cu")
		(at 78.15 149)
		(property "Reference" "TP22"
			(at 0 -0.731898 0)
			(layer "F.SilkS")
			(hide yes)
			(effects
				(font
					(size 0.7 0.7)
					(thickness 0.15)
				)
				(justify left bottom)
			)
		)
		(property "Value" "TP_1mm_SMD"
			(at 0 1.4 0)
			(layer "F.Fab")
			(effects
				(font
					(size 0.7 0.7)
					(thickness 0.15)
				)
				(justify left bottom)
			)
		)
		(property "Author" "Antmicro"
			(at 0 0 0)
			(layer "F.Fab")
			(hide yes)
			(effects
				(font
					(size 1 1)
					(thickness 0.15)
				)
			)
		)
		(property "License" "Apache-2.0"
			(at 0 0 0)
			(layer "F.Fab")
			(hide yes)
			(effects
				(font
					(size 1 1)
					(thickness 0.15)
				)
			)
		)
		(property "MPN" ""
			(at 0 0 0)
			(layer "F.Fab")
			(hide yes)
			(effects
				(font
					(size 1 1)
					(thickness 0.15)
				)
			)
		)
		(property "Manufacturer" ""
			(at 0 0 0)
			(layer "F.Fab")
			(hide yes)
			(effects
				(font
					(size 1 1)
					(thickness 0.15)
				)
			)
		)
		(sheetname "/Debug FTDI/")
		(sheetfile "debug-ftdi.kicad_sch")
		(attr exclude_from_pos_files)
		(pad "1" smd circle
			(at 0 0)
			(size 1 1)
			(layers "F.Cu" "F.Mask")
			(net 2 "/Debug FTDI/VBUS")
			(pinfunction "1")
			(pintype "passive")
		)
	)
)
